FILE_TYPE = MACRO_DRAWING;
SET COLOR_WIRE YELLOW;
SET COLOR_PROP MONO;
SET COLOR_DOT WHITE;
SET COLOR_ARC YELLOW;
SET COLOR_BODY GREEN;
SET COLOR_NOTE MONO;
SET PROP_DISPLAY VALUE;
SET PAGE_NUMBER P148;
FORCEADD W_VCC_CIRCLE..1
(-5875 3625);
FORCEPROP 3 LASTPIN (-5875 3625) SIG_NAME VCC_D_3V3\g
J 0
(-5865 3635);
DISPLAY 0.659574 (-5865 3635);
PAINT MONO (-5865 3635);
DISPLAY INVISIBLE (-5865 3635);
FORCEPROP 1 LAST HDL_POWER VCC_D_3V3
J 1
(-5854 3700);
DISPLAY 0.680851 (-5854 3700);
PAINT ORANGE (-5854 3700);
FORCEPROP 1 LAST BODY_TYPE PLUMBING
J 0
(-5863 3619);
DISPLAY 0.340426 (-5863 3619);
PAINT GREEN (-5863 3619);
DISPLAY INVISIBLE (-5863 3619);
FORCEPROP 1 LAST CDS_LMAN_SYM_OUTLINE -100,100,100,-100
J 0
(-5875 3625);
DISPLAY 0.468085 (-5875 3625);
PAINT GREEN (-5875 3625);
DISPLAY INVISIBLE (-5875 3625);
FORCEPROP 2 LAST CDS_LIB w_power
J 0
(-5875 3625);
PAINT MONO (-5875 3625);
DISPLAY INVISIBLE (-5875 3625);
FORCEPROP 1 LAST PATH I10
J 0
(-5875 3625);
DISPLAY 0.617021 (-5875 3625);
PAINT GREEN (-5875 3625);
DISPLAY INVISIBLE (-5875 3625);
FORCEADD OFFPAGE..1
(-5200 2425);
FORCEPROP 2 LAST $XR1 191 
J 0
(-5572 2425);
DISPLAY 0.638298 (-5572 2425);
PAINT MONO (-5572 2425);
FORCEPROP 2 LAST $XR0 118 
J 0
(-5452 2425);
DISPLAY 0.638298 (-5452 2425);
PAINT MONO (-5452 2425);
FORCEPROP 2 LAST CDS_LIB mstr_standard
J 0
(-5200 2425);
PAINT MONO (-5200 2425);
DISPLAY INVISIBLE (-5200 2425);
FORCEPROP 2 LAST BOM_COST SM_CONTROLLER
J 0
(-4750 2475);
PAINT MONO (-4750 2475);
DISPLAY INVISIBLE (-4750 2475);
FORCEPROP 2 LAST ROOM BMC
J 0
(-5450 2500);
DISPLAY 1.361702 (-5450 2500);
PAINT ORANGE (-5450 2500);
DISPLAY INVISIBLE (-5450 2500);
FORCEPROP 1 LAST OFFPAGE TRUE
J 0
(-4875 2300);
DISPLAY 0.872340 (-4875 2300);
PAINT GREEN (-4875 2300);
DISPLAY INVISIBLE (-4875 2300);
FORCEPROP 1 LAST COMMENT_BODY TRUE
J 0
(-5075 2325);
DISPLAY 0.872340 (-5075 2325);
PAINT GREEN (-5075 2325);
DISPLAY INVISIBLE (-5075 2325);
FORCEPROP 2 LAST PATH I12
J 0
(-5150 2500);
DISPLAY 1.021277 (-5150 2500);
PAINT ORANGE (-5150 2500);
DISPLAY INVISIBLE (-5150 2500);
FORCEADD OFFPAGE..1
(-5200 2375);
FORCEPROP 2 LAST $XR1 190 
J 0
(-5572 2375);
DISPLAY 0.638298 (-5572 2375);
PAINT MONO (-5572 2375);
FORCEPROP 2 LAST $XR0 118 
J 0
(-5452 2375);
DISPLAY 0.638298 (-5452 2375);
PAINT MONO (-5452 2375);
FORCEPROP 1 LAST COMMENT_BODY TRUE
J 0
(-5075 2275);
DISPLAY 0.872340 (-5075 2275);
PAINT GREEN (-5075 2275);
DISPLAY INVISIBLE (-5075 2275);
FORCEPROP 1 LAST OFFPAGE TRUE
J 0
(-4875 2250);
DISPLAY 0.872340 (-4875 2250);
PAINT GREEN (-4875 2250);
DISPLAY INVISIBLE (-4875 2250);
FORCEPROP 2 LAST ROOM BMC
J 0
(-5450 2450);
DISPLAY 1.361702 (-5450 2450);
PAINT ORANGE (-5450 2450);
DISPLAY INVISIBLE (-5450 2450);
FORCEPROP 2 LAST BOM_COST SM_CONTROLLER
J 0
(-4750 2425);
PAINT MONO (-4750 2425);
DISPLAY INVISIBLE (-4750 2425);
FORCEPROP 2 LAST CDS_LIB mstr_standard
J 0
(-5200 2375);
PAINT MONO (-5200 2375);
DISPLAY INVISIBLE (-5200 2375);
FORCEPROP 2 LAST PATH I13
J 0
(-5150 2450);
DISPLAY 1.021277 (-5150 2450);
PAINT ORANGE (-5150 2450);
DISPLAY INVISIBLE (-5150 2450);
FORCEADD W_VCC_CIRCLE..1
(-5675 2875);
FORCEPROP 3 LASTPIN (-5675 2875) SIG_NAME P1V2_AUX_BMC\g
J 0
(-5665 2885);
DISPLAY 0.659574 (-5665 2885);
PAINT MONO (-5665 2885);
DISPLAY INVISIBLE (-5665 2885);
FORCEPROP 1 LAST HDL_POWER P1V2_AUX_BMC
J 1
(-5654 2950);
DISPLAY 0.680851 (-5654 2950);
PAINT ORANGE (-5654 2950);
FORCEPROP 2 LAST CDS_LIB w_power
J 0
(-5675 2875);
PAINT MONO (-5675 2875);
DISPLAY INVISIBLE (-5675 2875);
FORCEPROP 1 LAST CDS_LMAN_SYM_OUTLINE -100,100,100,-100
J 0
(-5675 2875);
DISPLAY 0.468085 (-5675 2875);
PAINT GREEN (-5675 2875);
DISPLAY INVISIBLE (-5675 2875);
FORCEPROP 1 LAST BODY_TYPE PLUMBING
J 0
(-5663 2869);
DISPLAY 0.340426 (-5663 2869);
PAINT GREEN (-5663 2869);
DISPLAY INVISIBLE (-5663 2869);
FORCEPROP 1 LAST PATH I14
J 0
(-5675 2875);
DISPLAY 0.617021 (-5675 2875);
PAINT GREEN (-5675 2875);
DISPLAY INVISIBLE (-5675 2875);
FORCEADD W_VCC_CIRCLE..1
(-6300 3925);
FORCEPROP 3 LASTPIN (-6300 3925) SIG_NAME VCC_VA_3V3\g
J 0
(-6290 3935);
DISPLAY 0.659574 (-6290 3935);
PAINT MONO (-6290 3935);
DISPLAY INVISIBLE (-6290 3935);
FORCEPROP 1 LAST HDL_POWER VCC_VA_3V3
J 1
(-6279 4000);
DISPLAY 0.680851 (-6279 4000);
PAINT ORANGE (-6279 4000);
FORCEPROP 2 LAST CDS_LIB w_power
J 0
(-6300 3925);
PAINT MONO (-6300 3925);
DISPLAY INVISIBLE (-6300 3925);
FORCEPROP 1 LAST CDS_LMAN_SYM_OUTLINE -100,100,100,-100
J 0
(-6300 3925);
DISPLAY 0.468085 (-6300 3925);
PAINT GREEN (-6300 3925);
DISPLAY INVISIBLE (-6300 3925);
FORCEPROP 1 LAST BODY_TYPE PLUMBING
J 0
(-6288 3919);
DISPLAY 0.340426 (-6288 3919);
PAINT GREEN (-6288 3919);
DISPLAY INVISIBLE (-6288 3919);
FORCEPROP 1 LAST PATH I15
J 0
(-6300 3925);
DISPLAY 0.617021 (-6300 3925);
PAINT GREEN (-6300 3925);
DISPLAY INVISIBLE (-6300 3925);
FORCEADD RES..1
(-6550 3825);
FORCEPROP 1 LAST PACK_TYPE 0402
J 0
(-6450 3775);
DISPLAY 0.617021 (-6450 3775);
PAINT SKYBLUE (-6450 3775);
FORCEPROP 1 LAST MATERIAL CHIP
J 0
(-6775 3850);
DISPLAY 0.617021 (-6775 3850);
PAINT SKYBLUE (-6775 3850);
FORCEPROP 1 LAST VALUE 0.0
J 2
(-6375 3875);
DISPLAY 0.617021 (-6375 3875);
PAINT SKYBLUE (-6375 3875);
FORCEPROP 1 LAST LOCATION R25W59
J 0
(-6600 3875);
DISPLAY 0.617021 (-6600 3875);
PAINT AQUA (-6600 3875);
FORCEPROP 1 LAST TOLERANCE 5%
J 0
(-6625 3775);
DISPLAY 0.617021 (-6625 3775);
PAINT SKYBLUE (-6625 3775);
FORCEPROP 1 LAST WATTAGE 1/16W
J 2
(-6575 3700);
DISPLAY 0.510638 (-6575 3700);
PAINT SKYBLUE (-6575 3700);
DISPLAY INVISIBLE (-6575 3700);
FORCEPROP 1 LAST PART_NUMBER G21497-005
J 0
(-6475 3875);
DISPLAY 0.510638 (-6475 3875);
PAINT BLUE (-6475 3875);
DISPLAY INVISIBLE (-6475 3875);
FORCEPROP 0 LAST ROOM USB
J 0
(-6375 3925);
DISPLAY 1.021277 (-6375 3925);
PAINT ORANGE (-6375 3925);
DISPLAY INVISIBLE (-6375 3925);
FORCEPROP 0 LAST BOM_COST MIO_USB
J 0
(-6375 3975);
DISPLAY 1.021277 (-6375 3975);
PAINT ORANGE (-6375 3975);
DISPLAY INVISIBLE (-6375 3975);
FORCEPROP 2 LAST CDS_LIB mstr_discrete
J 0
(-6550 3825);
PAINT MONO (-6550 3825);
DISPLAY INVISIBLE (-6550 3825);
FORCEPROP 1 LAST PATH I16
J 0
(-6600 3975);
DISPLAY 0.978723 (-6600 3975);
PAINT WHITE (-6600 3975);
DISPLAY INVISIBLE (-6600 3975);
FORCEPROP 1 LASTPIN (-6650 3825) $PN 1
J 0
(-6638 3837);
DISPLAY 0.787234 (-6638 3837);
PAINT ORANGE (-6638 3837);
DISPLAY INVISIBLE (-6638 3837);
FORCEPROP 1 LASTPIN (-6450 3825) $PN 2
J 0
(-6488 3837);
DISPLAY 0.787234 (-6488 3837);
PAINT ORANGE (-6488 3837);
DISPLAY INVISIBLE (-6488 3837);
FORCEADD W_VCC_CIRCLE..1
(-6625 3550);
FORCEPROP 3 LASTPIN (-6625 3550) SIG_NAME VCC_D_PLL_3V3\g
J 0
(-6615 3560);
DISPLAY 0.659574 (-6615 3560);
PAINT MONO (-6615 3560);
DISPLAY INVISIBLE (-6615 3560);
FORCEPROP 1 LAST HDL_POWER VCC_D_PLL_3V3
J 1
(-6604 3625);
DISPLAY 0.680851 (-6604 3625);
PAINT ORANGE (-6604 3625);
FORCEPROP 1 LAST BODY_TYPE PLUMBING
J 0
(-6613 3544);
DISPLAY 0.340426 (-6613 3544);
PAINT GREEN (-6613 3544);
DISPLAY INVISIBLE (-6613 3544);
FORCEPROP 2 LAST CDS_LIB w_power
J 0
(-6625 3550);
PAINT MONO (-6625 3550);
DISPLAY INVISIBLE (-6625 3550);
FORCEPROP 1 LAST CDS_LMAN_SYM_OUTLINE -100,100,100,-100
J 0
(-6625 3550);
DISPLAY 0.468085 (-6625 3550);
PAINT GREEN (-6625 3550);
DISPLAY INVISIBLE (-6625 3550);
FORCEPROP 1 LAST PATH I17
J 0
(-6625 3550);
DISPLAY 0.617021 (-6625 3550);
PAINT GREEN (-6625 3550);
DISPLAY INVISIBLE (-6625 3550);
FORCEADD P3V3_STBY..1
(-6900 4050);
FORCEPROP 3 LASTPIN (-6900 4000) SIG_NAME P3V3_STBY\g
J 0
(-6890 4010);
DISPLAY 0.659574 (-6890 4010);
PAINT MONO (-6890 4010);
DISPLAY INVISIBLE (-6890 4010);
FORCEPROP 1 LAST HDL_POWER P3V3_STBY
J 0
(-7200 3925);
DISPLAY 0.872340 (-7200 3925);
PAINT ORANGE (-7200 3925);
DISPLAY INVISIBLE (-7200 3925);
FORCEPROP 1 LAST BODY_TYPE PLUMBING
J 0
(-6945 4007);
DISPLAY 0.340426 (-6945 4007);
PAINT GREEN (-6945 4007);
DISPLAY INVISIBLE (-6945 4007);
FORCEPROP 1 LAST SIZE 1B
J 0
(-6855 4072);
DISPLAY 0.340426 (-6855 4072);
PAINT GREEN (-6855 4072);
DISPLAY INVISIBLE (-6855 4072);
FORCEPROP 2 LAST CDS_LIB mstr_symbols
J 0
(-6900 4050);
PAINT MONO (-6900 4050);
DISPLAY INVISIBLE (-6900 4050);
FORCEPROP 1 LAST VOLTAGE 3.3V
J 0
(-6945 4007);
DISPLAY 0.340426 (-6945 4007);
PAINT GREEN (-6945 4007);
DISPLAY INVISIBLE (-6945 4007);
FORCEPROP 1 LAST PATH I18
J 0
(-6855 4052);
DISPLAY 0.340426 (-6855 4052);
PAINT GREEN (-6855 4052);
DISPLAY INVISIBLE (-6855 4052);
FORCEADD W_VCC_CIRCLE..1
(-6225 2150);
FORCEPROP 3 LASTPIN (-6225 2150) SIG_NAME P1V15_AUX_BMC\g
J 0
(-6215 2160);
DISPLAY 0.659574 (-6215 2160);
PAINT MONO (-6215 2160);
DISPLAY INVISIBLE (-6215 2160);
FORCEPROP 1 LAST HDL_POWER P1V15_AUX_BMC
J 1
(-6204 2225);
DISPLAY 0.680851 (-6204 2225);
PAINT ORANGE (-6204 2225);
FORCEPROP 1 LAST CDS_LMAN_SYM_OUTLINE -100,100,100,-100
J 0
(-6225 2150);
DISPLAY 0.468085 (-6225 2150);
PAINT GREEN (-6225 2150);
DISPLAY INVISIBLE (-6225 2150);
FORCEPROP 2 LAST CDS_LIB w_power
J 0
(-6225 2150);
PAINT MONO (-6225 2150);
DISPLAY INVISIBLE (-6225 2150);
FORCEPROP 1 LAST BODY_TYPE PLUMBING
J 0
(-6213 2144);
DISPLAY 0.340426 (-6213 2144);
PAINT GREEN (-6213 2144);
DISPLAY INVISIBLE (-6213 2144);
FORCEPROP 1 LAST PATH I19
J 0
(-6225 2150);
DISPLAY 0.617021 (-6225 2150);
PAINT GREEN (-6225 2150);
DISPLAY INVISIBLE (-6225 2150);
FORCEADD P3V3_STBY..1
(-2250 4625);
FORCEPROP 3 LASTPIN (-2250 4575) SIG_NAME P3V3_STBY\g
J 0
(-2240 4585);
DISPLAY 0.659574 (-2240 4585);
PAINT MONO (-2240 4585);
DISPLAY INVISIBLE (-2240 4585);
FORCEPROP 2 LAST CDS_LIB mstr_symbols
J 0
(-2250 4625);
PAINT MONO (-2250 4625);
DISPLAY INVISIBLE (-2250 4625);
FORCEPROP 1 LAST VOLTAGE 3.3V
J 0
(-2295 4582);
DISPLAY 0.340426 (-2295 4582);
PAINT GREEN (-2295 4582);
DISPLAY INVISIBLE (-2295 4582);
FORCEPROP 1 LAST SIZE 1B
J 0
(-2205 4647);
DISPLAY 0.340426 (-2205 4647);
PAINT GREEN (-2205 4647);
DISPLAY INVISIBLE (-2205 4647);
FORCEPROP 1 LAST BODY_TYPE PLUMBING
J 0
(-2295 4582);
DISPLAY 0.340426 (-2295 4582);
PAINT GREEN (-2295 4582);
DISPLAY INVISIBLE (-2295 4582);
FORCEPROP 1 LAST HDL_POWER P3V3_STBY
J 0
(-2550 4500);
DISPLAY 0.872340 (-2550 4500);
PAINT ORANGE (-2550 4500);
DISPLAY INVISIBLE (-2550 4500);
FORCEPROP 1 LAST PATH I2
J 0
(-2205 4627);
DISPLAY 0.340426 (-2205 4627);
PAINT GREEN (-2205 4627);
DISPLAY INVISIBLE (-2205 4627);
FORCEADD CAP_A..1
(-6925 2100);
FORCEPROP 1 LAST VALUE 1.0UF
J 0
(-6875 2150);
DISPLAY 0.617021 (-6875 2150);
PAINT SKYBLUE (-6875 2150);
FORCEPROP 1 LAST TOLERANCE 10%
J 0
(-6875 2050);
DISPLAY 0.617021 (-6875 2050);
PAINT SKYBLUE (-6875 2050);
FORCEPROP 1 LAST VOLTAGE 6.3V
J 0
(-6875 2100);
DISPLAY 0.617021 (-6875 2100);
PAINT SKYBLUE (-6875 2100);
FORCEPROP 1 LASTPIN (-6925 2200) $PN 1
J 0
(-6915 2180);
DISPLAY 0.617021 (-6915 2180);
PAINT ORANGE (-6915 2180);
FORCEPROP 1 LAST PART_NUMBER D97712-004
J 0
(-6875 1950);
DISPLAY 0.617021 (-6875 1950);
PAINT BLUE (-6875 1950);
FORCEPROP 1 LAST MATERIAL X6S
J 0
(-6875 2000);
DISPLAY 0.617021 (-6875 2000);
PAINT SKYBLUE (-6875 2000);
FORCEPROP 1 LAST PACK_TYPE 0402V
J 0
(-6875 1900);
DISPLAY 0.617021 (-6875 1900);
PAINT SKYBLUE (-6875 1900);
FORCEPROP 1 LASTPIN (-6925 2000) $PN 2
J 0
(-6915 1980);
DISPLAY 0.617021 (-6915 1980);
PAINT ORANGE (-6915 1980);
FORCEPROP 1 LAST LOCATION C1T21
J 0
(-6875 2200);
DISPLAY 0.617021 (-6875 2200);
PAINT AQUA (-6875 2200);
FORCEPROP 0 LAST ROOM BMC
J 0
(-6875 2250);
DISPLAY 1.021277 (-6875 2250);
PAINT ORANGE (-6875 2250);
DISPLAY INVISIBLE (-6875 2250);
FORCEPROP 2 LAST SEC 1
J 0
(-6875 2300);
DISPLAY 0.680851 (-6875 2300);
PAINT MONO (-6875 2300);
DISPLAY INVISIBLE (-6875 2300);
FORCEPROP 2 LAST SEC_TYPE 0402V
J 0
(-6875 2300);
DISPLAY 1.021277 (-6875 2300);
PAINT ORANGE (-6875 2300);
DISPLAY INVISIBLE (-6875 2300);
FORCEPROP 2 LAST CDS_SEC 1
J 0
(-6875 2250);
PAINT ORANGE (-6875 2250);
DISPLAY INVISIBLE (-6875 2250);
FORCEPROP 2 LAST CDS_LIB dev_discrete
J 0
(-6925 2100);
PAINT ORANGE (-6925 2100);
DISPLAY INVISIBLE (-6925 2100);
FORCEPROP 0 LAST BOM_COST SM_CONTROLLER
J 0
(-6875 2300);
DISPLAY 1.021277 (-6875 2300);
PAINT ORANGE (-6875 2300);
DISPLAY INVISIBLE (-6875 2300);
FORCEPROP 2 LAST CDS_LOCATION C1T21
J 0
(-6875 2200);
DISPLAY 0.617021 (-6875 2200);
PAINT AQUA (-6875 2200);
DISPLAY INVISIBLE (-6875 2200);
FORCEPROP 1 LAST PATH I20
J 0
(-6875 2250);
DISPLAY 0.978723 (-6875 2250);
PAINT WHITE (-6875 2250);
DISPLAY INVISIBLE (-6875 2250);
FORCEADD PVCCIO_CPU0..1
(-6925 2375);
FORCEPROP 3 LASTPIN (-6925 2325) SIG_NAME PVCCIO_CPU0\g
J 0
(-6915 2335);
DISPLAY 0.659574 (-6915 2335);
PAINT MONO (-6915 2335);
DISPLAY INVISIBLE (-6915 2335);
FORCEPROP 1 LAST PATH I21
J 0
(-6875 2400);
DISPLAY 0.872340 (-6875 2400);
PAINT AQUA (-6875 2400);
DISPLAY INVISIBLE (-6875 2400);
FORCEPROP 1 LAST HDL_POWER PVCCIO_CPU0
J 1
(-6925 2425);
DISPLAY 0.872340 (-6925 2425);
PAINT GREEN (-6925 2425);
DISPLAY INVISIBLE (-6925 2425);
FORCEPROP 1 LAST BODY_TYPE PLUMBING
J 0
(-6970 2332);
DISPLAY 0.340426 (-6970 2332);
PAINT GREEN (-6970 2332);
DISPLAY INVISIBLE (-6970 2332);
FORCEPROP 1 LAST VOLTAGE 1.1V
J 0
(-6970 2332);
DISPLAY 0.340426 (-6970 2332);
PAINT SKYBLUE (-6970 2332);
DISPLAY INVISIBLE (-6970 2332);
FORCEPROP 2 LAST CDS_LIB mstr_symbols
J 0
(-6925 2375);
PAINT ORANGE (-6925 2375);
DISPLAY INVISIBLE (-6925 2375);
FORCEADD GND..1
(-6925 1850);
FORCEPROP 3 LASTPIN (-6925 1900) SIG_NAME GND\g
J 0
(-6915 1910);
DISPLAY 0.659574 (-6915 1910);
PAINT MONO (-6915 1910);
DISPLAY INVISIBLE (-6915 1910);
FORCEPROP 2 LAST CDS_LIB mstr_symbols
J 0
(-6925 1850);
PAINT ORANGE (-6925 1850);
DISPLAY INVISIBLE (-6925 1850);
FORCEPROP 1 LAST SIZE 1B
J 0
(-6850 1800);
DISPLAY 0.872340 (-6850 1800);
PAINT AQUA (-6850 1800);
DISPLAY INVISIBLE (-6850 1800);
FORCEPROP 1 LAST VOLTAGE 0.0V
J 0
(-6970 1807);
DISPLAY 0.340426 (-6970 1807);
PAINT SKYBLUE (-6970 1807);
DISPLAY INVISIBLE (-6970 1807);
FORCEPROP 1 LAST BODY_TYPE PLUMBING
J 0
(-6970 1807);
DISPLAY 0.340426 (-6970 1807);
PAINT GREEN (-6970 1807);
DISPLAY INVISIBLE (-6970 1807);
FORCEPROP 1 LAST HDL_POWER GND
J 0
(-6925 2000);
DISPLAY 0.872340 (-6925 2000);
PAINT GREEN (-6925 2000);
DISPLAY INVISIBLE (-6925 2000);
FORCEPROP 1 LAST PATH I22
J 0
(-6850 1850);
DISPLAY 0.872340 (-6850 1850);
PAINT AQUA (-6850 1850);
DISPLAY INVISIBLE (-6850 1850);
FORCEADD RES..1
(-5900 2475);
FORCEPROP 1 LAST TOLERANCE 1%
J 0
(-5900 2525);
DISPLAY 0.617021 (-5900 2525);
PAINT SKYBLUE (-5900 2525);
FORCEPROP 1 LASTPIN (-6000 2475) $PN 1
J 0
(-5988 2487);
DISPLAY 0.617021 (-5988 2487);
PAINT ORANGE (-5988 2487);
FORCEPROP 1 LASTPIN (-5800 2475) $PN 2
J 0
(-5838 2487);
DISPLAY 0.617021 (-5838 2487);
PAINT ORANGE (-5838 2487);
FORCEPROP 1 LAST LOCATION R25W75
J 0
(-6450 2475);
DISPLAY 0.617021 (-6450 2475);
PAINT AQUA (-6450 2475);
FORCEPROP 1 LAST VALUE 33.2
J 2
(-6075 2475);
DISPLAY 0.617021 (-6075 2475);
PAINT SKYBLUE (-6075 2475);
FORCEPROP 1 LAST PACK_TYPE 0402
J 0
(-5975 2525);
DISPLAY 0.617021 (-5975 2525);
PAINT SKYBLUE (-5975 2525);
FORCEPROP 1 LAST WATTAGE 1/16W
J 2
(-6200 2475);
DISPLAY 0.617021 (-6200 2475);
PAINT SKYBLUE (-6200 2475);
FORCEPROP 1 LAST PATH I23
J 0
(-5950 2625);
DISPLAY 0.978723 (-5950 2625);
PAINT WHITE (-5950 2625);
DISPLAY INVISIBLE (-5950 2625);
FORCEPROP 0 LAST CDS_SEC 1
J 0
(-5950 2625);
PAINT MONO (-5950 2625);
DISPLAY INVISIBLE (-5950 2625);
FORCEPROP 2 LAST SEC 1
J 0
(-5950 2675);
DISPLAY 0.680851 (-5950 2675);
PAINT MONO (-5950 2675);
DISPLAY INVISIBLE (-5950 2675);
FORCEPROP 2 LAST SEC_TYPE 0402
J 0
(-5950 2675);
DISPLAY 1.021277 (-5950 2675);
PAINT ORANGE (-5950 2675);
DISPLAY INVISIBLE (-5950 2675);
FORCEPROP 0 LAST BOM_COST SM_CONTROLLER
J 0
(-5950 2675);
DISPLAY 1.021277 (-5950 2675);
PAINT ORANGE (-5950 2675);
DISPLAY INVISIBLE (-5950 2675);
FORCEPROP 0 LAST ROOM BMC
J 0
(-5950 2625);
DISPLAY 1.021277 (-5950 2625);
PAINT ORANGE (-5950 2625);
DISPLAY INVISIBLE (-5950 2625);
FORCEPROP 2 LAST CDS_LIB mstr_discrete
J 0
(-5900 2475);
PAINT ORANGE (-5900 2475);
DISPLAY INVISIBLE (-5900 2475);
FORCEPROP 1 LAST MATERIAL CHIP
J 0
(-6150 2375);
DISPLAY 0.617021 (-6150 2375);
PAINT SKYBLUE (-6150 2375);
DISPLAY INVISIBLE (-6150 2375);
FORCEPROP 1 LAST PART_NUMBER G21796-074
J 0
(-5950 2575);
DISPLAY 0.617021 (-5950 2575);
PAINT BLUE (-5950 2575);
DISPLAY INVISIBLE (-5950 2575);
FORCEPROP 2 LAST CDS_LOCATION R25W75
J 0
(-6450 2475);
DISPLAY 0.617021 (-6450 2475);
PAINT AQUA (-6450 2475);
DISPLAY INVISIBLE (-6450 2475);
FORCEADD OFFPAGE..1
(-7525 2475);
FORCEPROP 2 LAST $XR1 120 
J 0
(-7897 2475);
DISPLAY 0.638298 (-7897 2475);
PAINT MONO (-7897 2475);
FORCEPROP 2 LAST $XR0 191 
J 0
(-7777 2475);
DISPLAY 0.638298 (-7777 2475);
PAINT MONO (-7777 2475);
FORCEPROP 2 LAST CDS_LIB mstr_standard
J 0
(-7525 2475);
PAINT MONO (-7525 2475);
DISPLAY INVISIBLE (-7525 2475);
FORCEPROP 2 LAST PATH I25
J 0
(-7475 2550);
DISPLAY 1.021277 (-7475 2550);
PAINT ORANGE (-7475 2550);
DISPLAY INVISIBLE (-7475 2550);
FORCEPROP 1 LAST OFFPAGE TRUE
J 0
(-7200 2350);
DISPLAY 0.872340 (-7200 2350);
PAINT GREEN (-7200 2350);
DISPLAY INVISIBLE (-7200 2350);
FORCEPROP 1 LAST COMMENT_BODY TRUE
J 0
(-7400 2375);
DISPLAY 0.872340 (-7400 2375);
PAINT GREEN (-7400 2375);
DISPLAY INVISIBLE (-7400 2375);
FORCEADD W_VCC_CIRCLE..1
(-5350 4375);
FORCEPROP 3 LASTPIN (-5350 4375) SIG_NAME VCC_ADCAV3V3\g
J 0
(-5340 4385);
DISPLAY 0.659574 (-5340 4385);
PAINT MONO (-5340 4385);
DISPLAY INVISIBLE (-5340 4385);
FORCEPROP 1 LAST HDL_POWER VCC_ADCAV3V3
J 1
(-5329 4450);
DISPLAY 0.680851 (-5329 4450);
PAINT ORANGE (-5329 4450);
FORCEPROP 1 LAST BODY_TYPE PLUMBING
J 0
(-5338 4369);
DISPLAY 0.340426 (-5338 4369);
PAINT GREEN (-5338 4369);
DISPLAY INVISIBLE (-5338 4369);
FORCEPROP 1 LAST CDS_LMAN_SYM_OUTLINE -100,100,100,-100
J 0
(-5350 4375);
DISPLAY 0.468085 (-5350 4375);
PAINT GREEN (-5350 4375);
DISPLAY INVISIBLE (-5350 4375);
FORCEPROP 1 LAST PATH I26
J 0
(-5350 4375);
DISPLAY 0.617021 (-5350 4375);
PAINT GREEN (-5350 4375);
DISPLAY INVISIBLE (-5350 4375);
FORCEPROP 2 LAST CDS_LIB w_power
J 0
(-5350 4375);
PAINT MONO (-5350 4375);
DISPLAY INVISIBLE (-5350 4375);
FORCEADD W_VCC_CIRCLE..1
(-5300 2025);
FORCEPROP 3 LASTPIN (-5300 2025) SIG_NAME VCC_A_1V1\g
J 0
(-5290 2035);
DISPLAY 0.659574 (-5290 2035);
PAINT MONO (-5290 2035);
DISPLAY INVISIBLE (-5290 2035);
FORCEPROP 1 LAST HDL_POWER VCC_A_1V1
J 1
(-5279 2075);
DISPLAY 0.680851 (-5279 2075);
PAINT ORANGE (-5279 2075);
FORCEPROP 2 LAST CDS_LIB w_power
J 0
(-5300 2025);
PAINT MONO (-5300 2025);
DISPLAY INVISIBLE (-5300 2025);
FORCEPROP 1 LAST CDS_LMAN_SYM_OUTLINE -100,100,100,-100
J 0
(-5300 2025);
DISPLAY 0.468085 (-5300 2025);
PAINT GREEN (-5300 2025);
DISPLAY INVISIBLE (-5300 2025);
FORCEPROP 1 LAST BODY_TYPE PLUMBING
J 0
(-5288 2019);
DISPLAY 0.340426 (-5288 2019);
PAINT GREEN (-5288 2019);
DISPLAY INVISIBLE (-5288 2019);
FORCEPROP 1 LAST PATH I27
J 0
(-5300 2025);
DISPLAY 0.617021 (-5300 2025);
PAINT GREEN (-5300 2025);
DISPLAY INVISIBLE (-5300 2025);
FORCEADD AST2520A1-GP-GP..7
(-3600 2575);
FORCEPROP 1 LAST $LOCATION U25W4
J 0
(-4450 4700);
DISPLAY 0.617021 (-4450 4700);
PAINT GREEN (-4450 4700);
FORCEPROP 1 LAST VALUE AST2520A1-GP-GP
J 0
(-4450 425);
DISPLAY 0.617021 (-4450 425);
PAINT GREEN (-4450 425);
FORCEPROP 1 LAST CDS_LMAN_SYM_OUTLINE -850,2100,850,-2100
J 0
(-3600 2575);
DISPLAY 0.468085 (-3600 2575);
PAINT GREEN (-3600 2575);
DISPLAY INVISIBLE (-3600 2575);
FORCEPROP 1 LAST PACK_TYPE ASIC2-GB1
J 0
(-3600 2575);
DISPLAY 0.617021 (-3600 2575);
PAINT GREEN (-3600 2575);
DISPLAY INVISIBLE (-3600 2575);
FORCEPROP 1 LAST PATH I28
J 0
(-3600 2575);
DISPLAY 0.617021 (-3600 2575);
PAINT GREEN (-3600 2575);
DISPLAY INVISIBLE (-3600 2575);
FORCEPROP 1 LAST PART_NUMBER 071.2520A.M001
J 0
(-3600 2575);
DISPLAY 0.617021 (-3600 2575);
PAINT GREEN (-3600 2575);
DISPLAY INVISIBLE (-3600 2575);
FORCEPROP 2 LAST CDS_LIB w_hdl
J 0
(-3600 2575);
PAINT MONO (-3600 2575);
DISPLAY INVISIBLE (-3600 2575);
FORCEADD GND..1
(-2375 475);
FORCEPROP 3 LASTPIN (-2375 525) SIG_NAME GND\g
J 0
(-2365 535);
DISPLAY 0.659574 (-2365 535);
PAINT MONO (-2365 535);
DISPLAY INVISIBLE (-2365 535);
FORCEPROP 1 LAST VOLTAGE 0.0V
J 0
(-2420 432);
DISPLAY 0.340426 (-2420 432);
PAINT GREEN (-2420 432);
DISPLAY INVISIBLE (-2420 432);
FORCEPROP 1 LAST BODY_TYPE PLUMBING
J 0
(-2420 432);
DISPLAY 0.340426 (-2420 432);
PAINT GREEN (-2420 432);
DISPLAY INVISIBLE (-2420 432);
FORCEPROP 1 LAST SIZE 1B
J 0
(-2300 425);
DISPLAY 0.872340 (-2300 425);
PAINT AQUA (-2300 425);
DISPLAY INVISIBLE (-2300 425);
FORCEPROP 1 LAST HDL_POWER GND
J 0
(-2375 625);
DISPLAY 0.872340 (-2375 625);
PAINT GREEN (-2375 625);
DISPLAY INVISIBLE (-2375 625);
FORCEPROP 2 LAST CDS_LIB mstr_symbols
J 0
(-2375 475);
PAINT MONO (-2375 475);
DISPLAY INVISIBLE (-2375 475);
FORCEPROP 1 LAST PATH I3
J 0
(-2300 475);
DISPLAY 0.872340 (-2300 475);
PAINT AQUA (-2300 475);
DISPLAY INVISIBLE (-2300 475);
FORCEADD P3V3_STBY..1
(-5075 4775);
FORCEPROP 3 LASTPIN (-5075 4725) SIG_NAME P3V3_STBY\g
J 0
(-5065 4735);
DISPLAY 0.659574 (-5065 4735);
PAINT MONO (-5065 4735);
DISPLAY INVISIBLE (-5065 4735);
FORCEPROP 1 LAST VOLTAGE 3.3V
J 0
(-5120 4732);
DISPLAY 0.340426 (-5120 4732);
PAINT GREEN (-5120 4732);
DISPLAY INVISIBLE (-5120 4732);
FORCEPROP 1 LAST SIZE 1B
J 0
(-5030 4797);
DISPLAY 0.340426 (-5030 4797);
PAINT GREEN (-5030 4797);
DISPLAY INVISIBLE (-5030 4797);
FORCEPROP 1 LAST BODY_TYPE PLUMBING
J 0
(-5120 4732);
DISPLAY 0.340426 (-5120 4732);
PAINT GREEN (-5120 4732);
DISPLAY INVISIBLE (-5120 4732);
FORCEPROP 1 LAST HDL_POWER P3V3_STBY
J 0
(-5375 4650);
DISPLAY 0.872340 (-5375 4650);
PAINT ORANGE (-5375 4650);
DISPLAY INVISIBLE (-5375 4650);
FORCEPROP 2 LAST CDS_LIB mstr_symbols
J 0
(-5075 4775);
PAINT MONO (-5075 4775);
DISPLAY INVISIBLE (-5075 4775);
FORCEPROP 1 LAST PATH I4
J 0
(-5030 4777);
DISPLAY 0.340426 (-5030 4777);
PAINT GREEN (-5030 4777);
DISPLAY INVISIBLE (-5030 4777);
FORCEADD W_VCC_CIRCLE..1
(-6025 4275);
FORCEPROP 3 LASTPIN (-6025 4275) SIG_NAME VCC_DACAV3V3\g
J 0
(-6015 4285);
DISPLAY 0.659574 (-6015 4285);
PAINT MONO (-6015 4285);
DISPLAY INVISIBLE (-6015 4285);
FORCEPROP 1 LAST HDL_POWER VCC_DACAV3V3
J 1
(-6004 4350);
DISPLAY 0.680851 (-6004 4350);
PAINT ORANGE (-6004 4350);
FORCEPROP 2 LAST CDS_LIB w_power
J 0
(-6025 4275);
PAINT MONO (-6025 4275);
DISPLAY INVISIBLE (-6025 4275);
FORCEPROP 1 LAST CDS_LMAN_SYM_OUTLINE -100,100,100,-100
J 0
(-6025 4275);
DISPLAY 0.468085 (-6025 4275);
PAINT GREEN (-6025 4275);
DISPLAY INVISIBLE (-6025 4275);
FORCEPROP 1 LAST BODY_TYPE PLUMBING
J 0
(-6013 4269);
DISPLAY 0.340426 (-6013 4269);
PAINT GREEN (-6013 4269);
DISPLAY INVISIBLE (-6013 4269);
FORCEPROP 1 LAST PATH I6
J 0
(-6025 4275);
DISPLAY 0.617021 (-6025 4275);
PAINT GREEN (-6025 4275);
DISPLAY INVISIBLE (-6025 4275);
FORCEADD W_VCC_CIRCLE..1
(-6400 4175);
FORCEPROP 3 LASTPIN (-6400 4175) SIG_NAME P3V3_USB2A_ALG\g
J 0
(-6390 4185);
DISPLAY 0.659574 (-6390 4185);
PAINT MONO (-6390 4185);
DISPLAY INVISIBLE (-6390 4185);
FORCEPROP 1 LAST HDL_POWER P3V3_USB2A_ALG
J 1
(-6379 4250);
DISPLAY 0.680851 (-6379 4250);
PAINT ORANGE (-6379 4250);
FORCEPROP 2 LAST CDS_LIB w_power
J 0
(-6400 4175);
PAINT MONO (-6400 4175);
DISPLAY INVISIBLE (-6400 4175);
FORCEPROP 1 LAST CDS_LMAN_SYM_OUTLINE -100,100,100,-100
J 0
(-6400 4175);
DISPLAY 0.468085 (-6400 4175);
PAINT GREEN (-6400 4175);
DISPLAY INVISIBLE (-6400 4175);
FORCEPROP 1 LAST BODY_TYPE PLUMBING
J 0
(-6388 4169);
DISPLAY 0.340426 (-6388 4169);
PAINT GREEN (-6388 4169);
DISPLAY INVISIBLE (-6388 4169);
FORCEPROP 1 LAST PATH I7
J 0
(-6400 4175);
DISPLAY 0.617021 (-6400 4175);
PAINT GREEN (-6400 4175);
DISPLAY INVISIBLE (-6400 4175);
FORCEADD W_VCC_CIRCLE..1
(-5025 3700);
FORCEPROP 3 LASTPIN (-5025 3700) SIG_NAME VCC_PA_3V3\g
J 0
(-5015 3710);
DISPLAY 0.659574 (-5015 3710);
PAINT MONO (-5015 3710);
DISPLAY INVISIBLE (-5015 3710);
FORCEPROP 1 LAST HDL_POWER VCC_PA_3V3
J 1
(-5029 3775);
DISPLAY 0.680851 (-5029 3775);
PAINT ORANGE (-5029 3775);
FORCEPROP 2 LAST CDS_LIB w_power
J 0
(-5025 3700);
PAINT MONO (-5025 3700);
DISPLAY INVISIBLE (-5025 3700);
FORCEPROP 1 LAST CDS_LMAN_SYM_OUTLINE -100,100,100,-100
J 0
(-5025 3700);
DISPLAY 0.468085 (-5025 3700);
PAINT GREEN (-5025 3700);
DISPLAY INVISIBLE (-5025 3700);
FORCEPROP 1 LAST BODY_TYPE PLUMBING
J 0
(-5013 3694);
DISPLAY 0.340426 (-5013 3694);
PAINT GREEN (-5013 3694);
DISPLAY INVISIBLE (-5013 3694);
FORCEPROP 1 LAST PATH I8
J 0
(-5025 3700);
DISPLAY 0.617021 (-5025 3700);
PAINT GREEN (-5025 3700);
DISPLAY INVISIBLE (-5025 3700);
FORCEADD W_VCC_CIRCLE..1
(-5400 3975);
FORCEPROP 3 LASTPIN (-5400 3975) SIG_NAME VCC_D_3V3\g
J 0
(-5390 3985);
DISPLAY 0.659574 (-5390 3985);
PAINT MONO (-5390 3985);
DISPLAY INVISIBLE (-5390 3985);
FORCEPROP 1 LAST HDL_POWER VCC_D_3V3
J 1
(-5579 4000);
DISPLAY 0.680851 (-5579 4000);
PAINT ORANGE (-5579 4000);
FORCEPROP 1 LAST BODY_TYPE PLUMBING
J 0
(-5388 3969);
DISPLAY 0.340426 (-5388 3969);
PAINT GREEN (-5388 3969);
DISPLAY INVISIBLE (-5388 3969);
FORCEPROP 1 LAST CDS_LMAN_SYM_OUTLINE -100,100,100,-100
J 0
(-5400 3975);
DISPLAY 0.468085 (-5400 3975);
PAINT GREEN (-5400 3975);
DISPLAY INVISIBLE (-5400 3975);
FORCEPROP 2 LAST CDS_LIB w_power
J 0
(-5400 3975);
PAINT MONO (-5400 3975);
DISPLAY INVISIBLE (-5400 3975);
FORCEPROP 1 LAST PATH I9
J 0
(-5400 3975);
DISPLAY 0.617021 (-5400 3975);
PAINT GREEN (-5400 3975);
DISPLAY INVISIBLE (-5400 3975);
FORCEADD INTEL_CORP_BPAGE..1
(0 0);
FORCEPROP 1 LAST CDS_CON_LAST_MODIFIED Tue Dec 01 11:52:06 2015
J 0
(-1425 325);
DISPLAY 1.361702 (-1425 325);
PAINT GREEN (-1425 325);
DISPLAY INVISIBLE (-1425 325);
FORCEPROP 1 LAST CUSTOM_TXT_CDS <CURRENT_DESIGN_SHEET> OF <TOTAL_DESIGN_SHEETS>
J 0
(-500 25);
PAINT GREEN (-500 25);
FORCEPROP 1 LAST CUSTOM_TXT_CDS <CON_LAST_MODIFIED>
J 0
(-1925 350);
PAINT GREEN (-1925 350);
FORCEPROP 2 LAST CUSTOM_TXT_CDS <XR_PAGE_TITLE>
J 0
(-7890 5250);
DISPLAY 0.638298 (-7890 5250);
PAINT PINK (-7890 5250);
DISPLAY INVISIBLE (-7890 5250);
FORCEPROP 1 LAST SCH_TITLE BMC (7 OF 7)
J 0
(-7950 50);
DISPLAY 1.212766 (-7950 50);
PAINT ORANGE (-7950 50);
FORCEPROP 1 LAST SCH_ADDRESS3 Santa Clara, CA 95052-8119
J 0
(-3975 25);
DISPLAY 0.617021 (-3975 25);
PAINT GREEN (-3975 25);
FORCEPROP 1 LAST SCH_ADDRESS2 P.O. BOX 58119
J 0
(-3975 75);
DISPLAY 0.617021 (-3975 75);
PAINT GREEN (-3975 75);
FORCEPROP 1 LAST SCH_ADDRESS1 2200 Mission College Blvd.
J 0
(-3975 125);
DISPLAY 0.617021 (-3975 125);
PAINT GREEN (-3975 125);
FORCEPROP 1 LAST SCH_REV 2.420
J 0
(-250 150);
DISPLAY 0.978723 (-250 150);
PAINT YELLOW (-250 150);
FORCEPROP 1 LAST SCH_DEPT BESD
J 1
(-4450 100);
DISPLAY 1.212766 (-4450 100);
PAINT YELLOW (-4450 100);
FORCEPROP 1 LAST SCH_NUMBER H4694802
J 0
(-1300 150);
DISPLAY 1.212766 (-1300 150);
PAINT YELLOW (-1300 150);
FORCEPROP 1 LAST COMMENT_BODY TRUE
J 0
(12 12);
DISPLAY 0.617021 (12 12);
PAINT GREEN (12 12);
DISPLAY INVISIBLE (12 12);
FORCEPROP 2 LAST PAGE_BORDER TRUE
J 0
(-7890 5250);
DISPLAY 0.851064 (-7890 5250);
PAINT PINK (-7890 5250);
DISPLAY INVISIBLE (-7890 5250);
FORCEPROP 2 LAST CDS_LIB mstr_symbols
J 0
(0 0);
DISPLAY 1.361702 (0 0);
PAINT ORANGE (0 0);
DISPLAY INVISIBLE (0 0);
FORCEPROP 2 LAST CDS_XR_PAGE_TITLE CR-148 : @BASEBOARD_FAB2_LIB.BASEBOARD_FAB2(SCH_1):PAGE148
J 0
(-7890 5250);
DISPLAY 0.638298 (-7890 5250);
PAINT PINK (-7890 5250);
DISPLAY INVISIBLE (-7890 5250);
WIRE 16 -1 (-4600 2875)(-4950 2875);
WIRE 16 -1 (-4950 2875)(-4950 2925);
WIRE 16 -1 (-4950 2925)(-4600 2925);
WIRE 16 -1 (-4950 2925)(-4950 2975);
WIRE 16 -1 (-4950 2975)(-4600 2975);
WIRE 16 -1 (-4950 2975)(-4950 3025);
WIRE 16 -1 (-4950 3025)(-4950 3075);
WIRE 16 -1 (-4950 3025)(-4600 3025);
WIRE 16 -1 (-4950 3075)(-4600 3075);
WIRE 16 -1 (-4950 3075)(-4950 3125);
WIRE 16 -1 (-4950 3125)(-4600 3125);
WIRE 16 -1 (-4950 3125)(-4950 3175);
WIRE 16 -1 (-4950 3175)(-4600 3175);
WIRE 16 -1 (-4950 3175)(-4950 3225);
WIRE 16 -1 (-4950 3225)(-4600 3225);
WIRE 16 -1 (-4950 3225)(-4950 3275);
WIRE 16 -1 (-4950 3275)(-4600 3275);
WIRE 16 -1 (-4950 3275)(-4950 3325);
WIRE 16 -1 (-4950 3325)(-4600 3325);
WIRE 16 -1 (-4950 3325)(-4950 3375);
WIRE 16 -1 (-4950 3375)(-4600 3375);
WIRE 16 -1 (-4950 3375)(-4950 3425);
WIRE 16 -1 (-4950 3425)(-4600 3425);
WIRE 16 -1 (-4950 3425)(-4950 3475);
WIRE 16 -1 (-4950 3475)(-4600 3475);
WIRE 16 -1 (-4950 3475)(-4950 3575);
WIRE 16 -1 (-4950 3575)(-4600 3575);
WIRE 16 -1 (-4950 3575)(-5875 3575);
WIRE 16 -1 (-5875 3625)(-5875 3575);
WIRE 16 -1 (-5675 2575)(-4600 2575);
WIRE 16 -1 (-5675 2625)(-5675 2575);
WIRE 16 -1 (-4600 2625)(-5675 2625);
WIRE 16 -1 (-5675 2675)(-5675 2625);
WIRE 16 -1 (-4600 2675)(-5675 2675);
WIRE 16 -1 (-5675 2725)(-5675 2675);
WIRE 16 -1 (-4600 2725)(-5675 2725);
WIRE 16 -1 (-5675 2775)(-5675 2725);
WIRE 16 -1 (-4600 2775)(-5675 2775);
WIRE 16 -1 (-5675 2875)(-5675 2775);
WIRE 16 -1 (-4700 3875)(-4600 3875);
WIRE 16 -1 (-4700 3925)(-4700 3875);
WIRE 16 -1 (-4700 3925)(-4600 3925);
WIRE 16 -1 (-6300 3925)(-4700 3925);
WIRE 16 -1 (-4600 3525)(-6625 3525);
WIRE 16 -1 (-6625 3550)(-6625 3525);
WIRE 16 -1 (-6650 3825)(-6900 3825);
WIRE 16 -1 (-6900 3825)(-6900 4000);
WIRE 16 -1 (-4600 675)(-5700 675);
WIRE 16 -1 (-5700 725)(-5700 675);
WIRE 16 -1 (-4600 725)(-5700 725);
WIRE 16 -1 (-5700 775)(-5700 725);
WIRE 16 -1 (-4600 775)(-5700 775);
WIRE 16 -1 (-5700 825)(-5700 775);
WIRE 16 -1 (-4600 825)(-5700 825);
WIRE 16 -1 (-5700 875)(-5700 825);
WIRE 16 -1 (-4600 875)(-5700 875);
WIRE 16 -1 (-5700 925)(-5700 875);
WIRE 16 -1 (-4600 925)(-5700 925);
WIRE 16 -1 (-5700 975)(-5700 925);
WIRE 16 -1 (-4600 975)(-5700 975);
WIRE 16 -1 (-5700 1025)(-5700 975);
WIRE 16 -1 (-4600 1025)(-5700 1025);
WIRE 16 -1 (-5700 1075)(-5700 1025);
WIRE 16 -1 (-4600 1075)(-5700 1075);
WIRE 16 -1 (-5700 1125)(-5700 1075);
WIRE 16 -1 (-4600 1125)(-5700 1125);
WIRE 16 -1 (-5700 1175)(-5700 1125);
WIRE 16 -1 (-4600 1175)(-5700 1175);
WIRE 16 -1 (-5700 1225)(-5700 1175);
WIRE 16 -1 (-4600 1225)(-5700 1225);
WIRE 16 -1 (-5700 1275)(-5700 1225);
WIRE 16 -1 (-4600 1275)(-5700 1275);
WIRE 16 -1 (-5700 1325)(-5700 1275);
WIRE 16 -1 (-4600 1325)(-5700 1325);
WIRE 16 -1 (-5700 1375)(-5700 1325);
WIRE 16 -1 (-4600 1375)(-5700 1375);
WIRE 16 -1 (-5700 1425)(-5700 1375);
WIRE 16 -1 (-4600 1425)(-5700 1425);
WIRE 16 -1 (-5700 1475)(-5700 1425);
WIRE 16 -1 (-4600 1475)(-5700 1475);
WIRE 16 -1 (-5700 1525)(-5700 1475);
WIRE 16 -1 (-4600 1525)(-5700 1525);
WIRE 16 -1 (-5700 1575)(-5700 1525);
WIRE 16 -1 (-4600 1575)(-5700 1575);
WIRE 16 -1 (-5700 1625)(-5700 1575);
WIRE 16 -1 (-4600 1625)(-5700 1625);
WIRE 16 -1 (-5700 1675)(-5700 1625);
WIRE 16 -1 (-4600 1675)(-5700 1675);
WIRE 16 -1 (-5700 1725)(-5700 1675);
WIRE 16 -1 (-4600 1725)(-5700 1725);
WIRE 16 -1 (-5700 1775)(-5700 1725);
WIRE 16 -1 (-4600 1775)(-5700 1775);
WIRE 16 -1 (-5700 1825)(-5700 1775);
WIRE 16 -1 (-4600 1825)(-5700 1825);
WIRE 16 -1 (-5700 1825)(-5700 1875);
WIRE 16 -1 (-4600 1875)(-5700 1875);
WIRE 16 -1 (-5700 1875)(-5700 2075);
WIRE 16 -1 (-5700 2075)(-5700 2125);
WIRE 16 -1 (-5700 2075)(-6225 2075);
WIRE 16 -1 (-6225 2075)(-6225 2150);
WIRE 16 -1 (-5700 2225)(-5700 2125);
WIRE 16 -1 (-5700 2125)(-4600 2125);
WIRE 16 -1 (-4600 2225)(-5700 2225);
WIRE 16 -1 (-2600 4325)(-2250 4325);
WIRE 16 -1 (-2250 4375)(-2250 4325);
WIRE 16 -1 (-2250 4575)(-2250 4375);
WIRE 16 -1 (-2250 4375)(-2600 4375);
WIRE 16 -1 (-4600 2275)(-6925 2275);
WIRE 16 -1 (-6925 2325)(-6925 2275);
WIRE 16 -1 (-6925 2275)(-6925 2200);
WIRE 16 -1 (-6925 2000)(-6925 1900);
WIRE 16 -1 (-5350 4275)(-4600 4275);
WIRE 16 -1 (-5350 4275)(-5350 4375);
WIRE 16 -1 (-4700 2025)(-4600 2025);
WIRE 16 -1 (-4700 2025)(-4700 1975);
WIRE 16 -1 (-4600 1975)(-4700 1975);
WIRE 16 -1 (-4700 1975)(-5300 1975);
WIRE 16 -1 (-5300 2025)(-5300 1975);
WIRE 16 -1 (-2375 4075)(-2375 4025);
WIRE 16 -1 (-2375 4075)(-2600 4075);
WIRE 16 -1 (-2600 4025)(-2375 4025);
WIRE 16 -1 (-2375 4025)(-2375 3975);
WIRE 16 -1 (-2600 3975)(-2375 3975);
WIRE 16 -1 (-2375 3975)(-2375 3925);
WIRE 16 -1 (-2600 3925)(-2375 3925);
WIRE 16 -1 (-2375 3925)(-2375 3875);
WIRE 16 -1 (-2600 3875)(-2375 3875);
WIRE 16 -1 (-2375 3875)(-2375 3825);
WIRE 16 -1 (-2600 3825)(-2375 3825);
WIRE 16 -1 (-2375 3825)(-2375 3775);
WIRE 16 -1 (-2600 3775)(-2375 3775);
WIRE 16 -1 (-2375 3775)(-2375 3725);
WIRE 16 -1 (-2600 3725)(-2375 3725);
WIRE 16 -1 (-2375 3725)(-2375 3675);
WIRE 16 -1 (-2600 3675)(-2375 3675);
WIRE 16 -1 (-2375 3675)(-2375 3625);
WIRE 16 -1 (-2600 3625)(-2375 3625);
WIRE 16 -1 (-2375 3625)(-2375 3575);
WIRE 16 -1 (-2600 3575)(-2375 3575);
WIRE 16 -1 (-2375 3575)(-2375 3525);
WIRE 16 -1 (-2600 3525)(-2375 3525);
WIRE 16 -1 (-2375 3525)(-2375 3475);
WIRE 16 -1 (-2600 3475)(-2375 3475);
WIRE 16 -1 (-2375 3475)(-2375 3425);
WIRE 16 -1 (-2600 3425)(-2375 3425);
WIRE 16 -1 (-2375 3425)(-2375 3375);
WIRE 16 -1 (-2600 3375)(-2375 3375);
WIRE 16 -1 (-2375 3375)(-2375 3325);
WIRE 16 -1 (-2600 3325)(-2375 3325);
WIRE 16 -1 (-2375 3325)(-2375 3275);
WIRE 16 -1 (-2600 3275)(-2375 3275);
WIRE 16 -1 (-2375 3275)(-2375 3225);
WIRE 16 -1 (-2600 3225)(-2375 3225);
WIRE 16 -1 (-2375 3225)(-2375 3175);
WIRE 16 -1 (-2600 3175)(-2375 3175);
WIRE 16 -1 (-2375 3175)(-2375 3125);
WIRE 16 -1 (-2600 3125)(-2375 3125);
WIRE 16 -1 (-2375 3125)(-2375 3075);
WIRE 16 -1 (-2600 3075)(-2375 3075);
WIRE 16 -1 (-2375 3075)(-2375 3025);
WIRE 16 -1 (-2600 3025)(-2375 3025);
WIRE 16 -1 (-2375 3025)(-2375 2975);
WIRE 16 -1 (-2600 2975)(-2375 2975);
WIRE 16 -1 (-2375 2975)(-2375 2925);
WIRE 16 -1 (-2600 2925)(-2375 2925);
WIRE 16 -1 (-2375 2925)(-2375 2875);
WIRE 16 -1 (-2600 2875)(-2375 2875);
WIRE 16 -1 (-2375 2875)(-2375 2825);
WIRE 16 -1 (-2600 2825)(-2375 2825);
WIRE 16 -1 (-2375 2825)(-2375 2775);
WIRE 16 -1 (-2600 2775)(-2375 2775);
WIRE 16 -1 (-2375 2775)(-2375 2725);
WIRE 16 -1 (-2600 2725)(-2375 2725);
WIRE 16 -1 (-2375 2725)(-2375 2675);
WIRE 16 -1 (-2600 2675)(-2375 2675);
WIRE 16 -1 (-2375 2675)(-2375 2625);
WIRE 16 -1 (-2600 2625)(-2375 2625);
WIRE 16 -1 (-2375 2625)(-2375 2575);
WIRE 16 -1 (-2600 2575)(-2375 2575);
WIRE 16 -1 (-2375 2575)(-2375 2525);
WIRE 16 -1 (-2600 2525)(-2375 2525);
WIRE 16 -1 (-2375 2525)(-2375 2475);
WIRE 16 -1 (-2600 2475)(-2375 2475);
WIRE 16 -1 (-2375 2475)(-2375 2425);
WIRE 16 -1 (-2600 2425)(-2375 2425);
WIRE 16 -1 (-2375 2425)(-2375 2375);
WIRE 16 -1 (-2600 2375)(-2375 2375);
WIRE 16 -1 (-2375 2375)(-2375 2325);
WIRE 16 -1 (-2600 2325)(-2375 2325);
WIRE 16 -1 (-2375 2325)(-2375 2275);
WIRE 16 -1 (-2600 2275)(-2375 2275);
WIRE 16 -1 (-2375 2275)(-2375 2225);
WIRE 16 -1 (-2600 2225)(-2375 2225);
WIRE 16 -1 (-2375 2225)(-2375 2175);
WIRE 16 -1 (-2600 2175)(-2375 2175);
WIRE 16 -1 (-2375 2175)(-2375 2125);
WIRE 16 -1 (-2600 2125)(-2375 2125);
WIRE 16 -1 (-2375 2125)(-2375 2075);
WIRE 16 -1 (-2600 2075)(-2375 2075);
WIRE 16 -1 (-2375 2075)(-2375 2025);
WIRE 16 -1 (-2600 2025)(-2375 2025);
WIRE 16 -1 (-2375 2025)(-2375 1975);
WIRE 16 -1 (-2600 1975)(-2375 1975);
WIRE 16 -1 (-2375 1975)(-2375 1925);
WIRE 16 -1 (-2600 1925)(-2375 1925);
WIRE 16 -1 (-2375 1925)(-2375 1875);
WIRE 16 -1 (-2600 1875)(-2375 1875);
WIRE 16 -1 (-2375 1875)(-2375 1825);
WIRE 16 -1 (-2600 1825)(-2375 1825);
WIRE 16 -1 (-2375 1825)(-2375 1775);
WIRE 16 -1 (-2600 1775)(-2375 1775);
WIRE 16 -1 (-2375 1775)(-2375 1725);
WIRE 16 -1 (-2600 1725)(-2375 1725);
WIRE 16 -1 (-2375 1725)(-2375 1675);
WIRE 16 -1 (-2600 1675)(-2375 1675);
WIRE 16 -1 (-2375 1675)(-2375 1625);
WIRE 16 -1 (-2600 1625)(-2375 1625);
WIRE 16 -1 (-2375 1625)(-2375 1575);
WIRE 16 -1 (-2600 1575)(-2375 1575);
WIRE 16 -1 (-2375 1575)(-2375 1525);
WIRE 16 -1 (-2600 1525)(-2375 1525);
WIRE 16 -1 (-2375 1525)(-2375 1475);
WIRE 16 -1 (-2600 1475)(-2375 1475);
WIRE 16 -1 (-2375 1475)(-2375 1425);
WIRE 16 -1 (-2600 1425)(-2375 1425);
WIRE 16 -1 (-2375 1425)(-2375 1375);
WIRE 16 -1 (-2600 1375)(-2375 1375);
WIRE 16 -1 (-2375 1375)(-2375 1325);
WIRE 16 -1 (-2600 1325)(-2375 1325);
WIRE 16 -1 (-2375 1325)(-2375 1275);
WIRE 16 -1 (-2600 1275)(-2375 1275);
WIRE 16 -1 (-2375 1275)(-2375 1225);
WIRE 16 -1 (-2600 1225)(-2375 1225);
WIRE 16 -1 (-2375 1225)(-2375 1175);
WIRE 16 -1 (-2600 1175)(-2375 1175);
WIRE 16 -1 (-2375 1175)(-2375 1125);
WIRE 16 -1 (-2600 1125)(-2375 1125);
WIRE 16 -1 (-2375 1125)(-2375 1075);
WIRE 16 -1 (-2600 1075)(-2375 1075);
WIRE 16 -1 (-2375 1075)(-2375 1025);
WIRE 16 -1 (-2600 1025)(-2375 1025);
WIRE 16 -1 (-2375 1025)(-2375 975);
WIRE 16 -1 (-2600 975)(-2375 975);
WIRE 16 -1 (-2375 975)(-2375 925);
WIRE 16 -1 (-2600 925)(-2375 925);
WIRE 16 -1 (-2375 925)(-2375 875);
WIRE 16 -1 (-2600 875)(-2375 875);
WIRE 16 -1 (-2375 875)(-2375 825);
WIRE 16 -1 (-2600 825)(-2375 825);
WIRE 16 -1 (-2375 825)(-2375 775);
WIRE 16 -1 (-2600 775)(-2375 775);
WIRE 16 -1 (-2375 775)(-2375 725);
WIRE 16 -1 (-2600 725)(-2375 725);
WIRE 16 -1 (-2375 725)(-2375 675);
WIRE 16 -1 (-2600 675)(-2375 675);
WIRE 16 -1 (-2375 675)(-2375 525);
WIRE 16 -1 (-4600 4375)(-4825 4375);
WIRE 16 -1 (-4825 4425)(-4825 4375);
WIRE 16 -1 (-4600 4425)(-4825 4425);
WIRE 16 -1 (-4825 4475)(-4825 4425);
WIRE 16 -1 (-4600 4475)(-4825 4475);
WIRE 16 -1 (-4825 4525)(-4825 4475);
WIRE 16 -1 (-4600 4525)(-4825 4525);
WIRE 16 -1 (-5075 4525)(-4825 4525);
WIRE 16 -1 (-5075 4725)(-5075 4525);
WIRE 16 -1 (-4600 4175)(-6025 4175);
WIRE 16 -1 (-6025 4175)(-6025 4225);
WIRE 16 -1 (-6025 4225)(-4600 4225);
WIRE 16 -1 (-6025 4225)(-6025 4275);
WIRE 16 -1 (-4600 4075)(-6400 4075);
WIRE 16 -1 (-6400 4075)(-6400 4175);
WIRE 16 -1 (-4750 3725)(-4600 3725);
WIRE 16 -1 (-4750 3675)(-4750 3725);
WIRE 16 -1 (-4600 3675)(-4750 3675);
WIRE 16 -1 (-4750 3675)(-5025 3675);
WIRE 16 -1 (-5025 3675)(-5025 3700);
WIRE 16 -1 (-5400 3975)(-4600 3975);
WIRE 16 -1 (-5150 2375)(-4600 2375);
FORCEPROP 2 LAST SIG_NAME FM_SLPS3_N
J 2
(-4775 2385);
DISPLAY 0.617021 (-4775 2385);
PAINT ORANGE (-4775 2385);
WIRE 16 -1 (-5150 2425)(-4600 2425);
FORCEPROP 2 LAST SIG_NAME FM_SLPS4_N
J 2
(-4800 2435);
DISPLAY 0.617021 (-4800 2435);
PAINT ORANGE (-4800 2435);
WIRE 16 -1 (-5800 2475)(-4600 2475);
FORCEPROP 2 LAST SIG_NAME FM_CPU1_FIVR_FAULT_LVT3_R_N
J 0
(-5635 2485);
DISPLAY 0.617021 (-5635 2485);
PAINT ORANGE (-5635 2485);
FORCEPROP 2 LASTPROP $XRERR UNIQUE?
J 0
(-5875 2485);
DISPLAY 0.638298 (-5875 2485);
PAINT MONO (-5875 2485);
DISPLAY INVISIBLE (-5875 2485);
WIRE 16 -1 (-6450 3825)(-4600 3825);
FORCEPROP 2 LAST SIG_NAME VCCBAT_TW12
J 0
(-6310 3835);
DISPLAY 0.680851 (-6310 3835);
PAINT ORANGE (-6310 3835);
FORCEPROP 2 LASTPROP $XRERR UNIQUE?
J 0
(-6550 3835);
DISPLAY 0.638298 (-6550 3835);
PAINT MONO (-6550 3835);
DISPLAY INVISIBLE (-6550 3835);
WIRE 16 -1 (-7475 2475)(-6000 2475);
FORCEPROP 2 LAST SIG_NAME FM_CPU1_FIVR_FAULT_LVT3_N
J 0
(-7335 2485);
DISPLAY 0.617021 (-7335 2485);
PAINT ORANGE (-7335 2485);
DOT 1 (-4950 3175);
DOT 1 (-5700 1725);
DOT 1 (-6925 2275);
DOT 1 (-5675 2725);
DOT 1 (-5700 775);
DOT 1 (-5700 725);
DOT 1 (-5700 825);
DOT 1 (-5700 875);
DOT 1 (-5700 925);
DOT 1 (-5700 975);
DOT 1 (-5700 1025);
DOT 1 (-5700 1175);
DOT 1 (-5700 1125);
DOT 1 (-5700 1225);
DOT 1 (-5700 1275);
DOT 1 (-5700 1325);
DOT 1 (-5700 1425);
DOT 1 (-5700 1375);
DOT 1 (-5700 1525);
DOT 1 (-5700 1475);
DOT 1 (-5700 1575);
DOT 1 (-5700 1675);
DOT 1 (-5700 1625);
DOT 1 (-5700 1775);
DOT 1 (-5700 1825);
DOT 1 (-5700 2075);
DOT 1 (-5700 2125);
DOT 1 (-5675 2625);
DOT 1 (-5675 2675);
DOT 1 (-5675 2775);
DOT 1 (-4950 2925);
DOT 1 (-4950 2975);
DOT 1 (-4950 3075);
DOT 1 (-4950 3125);
DOT 1 (-4950 3025);
DOT 1 (-4950 3225);
DOT 1 (-4950 3275);
DOT 1 (-4950 3325);
DOT 1 (-4950 3375);
DOT 1 (-4950 3475);
DOT 1 (-4950 3425);
DOT 1 (-4950 3575);
DOT 1 (-4750 3675);
DOT 1 (-6025 4225);
DOT 1 (-4825 4525);
DOT 1 (-4825 4475);
DOT 1 (-4825 4425);
DOT 1 (-4700 3925);
DOT 1 (-4700 1975);
DOT 1 (-5700 1875);
DOT 1 (-2250 4375);
DOT 1 (-2375 4025);
DOT 1 (-2375 3975);
DOT 1 (-2375 3925);
DOT 1 (-2375 3875);
DOT 1 (-2375 3825);
DOT 1 (-2375 3775);
DOT 1 (-2375 3725);
DOT 1 (-2375 3675);
DOT 1 (-2375 3625);
DOT 1 (-2375 3575);
DOT 1 (-2375 3525);
DOT 1 (-2375 3475);
DOT 1 (-2375 3375);
DOT 1 (-2375 3425);
DOT 1 (-2375 3325);
DOT 1 (-2375 3275);
DOT 1 (-2375 3225);
DOT 1 (-2375 3125);
DOT 1 (-2375 3175);
DOT 1 (-2375 2975);
DOT 1 (-2375 3025);
DOT 1 (-2375 3075);
DOT 1 (-2375 2925);
DOT 1 (-2375 2875);
DOT 1 (-2375 2825);
DOT 1 (-2375 2725);
DOT 1 (-2375 2775);
DOT 1 (-2375 2675);
DOT 1 (-2375 2625);
DOT 1 (-2375 2575);
DOT 1 (-2375 2525);
DOT 1 (-2375 2475);
DOT 1 (-2375 2425);
DOT 1 (-2375 2375);
DOT 1 (-2375 2325);
DOT 1 (-2375 2225);
DOT 1 (-2375 2275);
DOT 1 (-2375 2175);
DOT 1 (-2375 2125);
DOT 1 (-2375 2075);
DOT 1 (-2375 2025);
DOT 1 (-2375 1975);
DOT 1 (-2375 1925);
DOT 1 (-2375 1825);
DOT 1 (-2375 1875);
DOT 1 (-2375 1775);
DOT 1 (-2375 1725);
DOT 1 (-2375 1675);
DOT 1 (-2375 1625);
DOT 1 (-2375 1575);
DOT 1 (-2375 1525);
DOT 1 (-2375 1425);
DOT 1 (-2375 1475);
DOT 1 (-2375 1325);
DOT 1 (-2375 1375);
DOT 1 (-2375 1275);
DOT 1 (-2375 1225);
DOT 1 (-2375 1175);
DOT 1 (-2375 1075);
DOT 1 (-2375 1125);
DOT 1 (-2375 1025);
DOT 1 (-2375 975);
DOT 1 (-2375 925);
DOT 1 (-2375 875);
DOT 1 (-2375 825);
DOT 1 (-2375 775);
DOT 1 (-2375 725);
DOT 1 (-2375 675);
DOT 1 (-5700 1075);
FORCENOTE
ROOM=SM_CONTROLLER
(-7833 298) 0;
DISPLAY LEFT (-7833 298);
DISPLAY 0.617021 (-7833 298);
PAINT PURPLE (-7833 298);
FORCENOTE
POWER PIN T11 (OLD NAME: PV33D) SUPPLIES THE DDR PHY PLL POWER.
(-7425 3400) 0;
DISPLAY LEFT (-7425 3400);
DISPLAY 1.021277 (-7425 3400);
PAINT RED (-7425 3400);
QUIT
